FILE_TYPE = MULTI_PHYS_TABLE;

PART 'PCA9539RPW'

{========================================================================================}
:VALUE        | PART_TYPE | MATERIAL | PART_NUMBER    = STANDARD    | LIFECYCLE          | PART_NUMBER   | JEDEC_TYPE  | DESCRIPTION                      | MANUFTR | MANUF_PN     | RD_CMPLS_LVL | CMPLS_LVL | FROM_PJ     | CLASS | DIP_SMD | DATA                 | EE_CHECK_LIST | FP_ECN | PSL | CREATOR | STATUS | MSD  | ESD_CDM | ESD_HBM | ESD_MM | PIN_LENGTH_SHORT_PIN | PIN_LENGTH_LONG_PIN | CREATEDAY  ;
{========================================================================================}
 'PCA9539RPW' | 'SMLF'    | 'IC'     | 'AL009539K07'(!) = ''               | ''               | 'AL009539K07' |'TSSOP24XB'| 'IC OTHER(24P)PCA9539RPW(TSSOP)' | 'NXP'   | 'PCA9539RPW' | 'EP(V1)'     | 'EP(V1)'  | 'S5C-KEVIN' | 'IC'  | ''      | 'NXP_PCA9539RPW.pdf' | ''            | ''     | ''  | ''      | ''     | 'NA' | 'NA'    | 'NA'    | 'NA'   | '0 MILS'             | '0 MILS'            | '20180717'
 'PCA9539RPW' | 'SMLF'    | 'EMPTY'  | 'AL009539K07'(!) = ''               | ''               | 'AL009539K07' |'TSSOP24XB'| 'IC OTHER(24P)PCA9539RPW(TSSOP)' | 'NXP'   | 'PCA9539RPW' | 'EP(V1)'     | 'EP(V1)'  | 'S5C-KEVIN' | 'IC'  | ''      | 'NXP_PCA9539RPW.pdf' | ''            | ''     | ''  | ''      | ''     | 'NA' | 'NA'    | 'NA'    | 'NA'   | '0 MILS'             | '0 MILS'            | '20180717'

END_PART

END.

